# T6G (Grand Teton) — schematic netlist excerpt (pin names and nets, part order shuffled) for the footprints in the layout excerpt that follows; sources: Cadence DE-HDL packaged netlist, KiCad conversion of 04192023_DAF0TMB3IC0_F0TG_MB_C_brd_V02_OCP.brd

PC6622  Q_CAP  560PF 50V 10% EMPTY  pkg C0402  page 365 : A = SW_P0V9_RETIMER_CPU1_SW1 ; B = SW_P0V9_RETIMER_CPU1_SW1_RC
R1192  Q_RES  1K 1% CHIP  pkg 0402LF  page 140 : A = P3V3_AUX ; B = HP_LVC3_OCP_V3_2_PRSNT2_N
R1020  Q_RES  10K 1% CHIP  pkg 0201LF  page 287 : A = RST_RT_CPU0_P1_RESET_R_N ; B = GND

(kicad_pcb
	(version 20260206)
	(generator "pcbnew")
	(generator_version "10.0")
	(general
		(thickness 1.6)
		(legacy_teardrops no)
	)
	(paper "A4")
	(title_block
		(title "04192023_DAF0TMB3IC0_F0TG_MB_C_brd_V02_OCP.brd")
		(comment 1 "Grand Teton / footprints 4518-4520 of 8354")
	)
	(layers
		(0 "F.Cu" signal "TOP")
		(4 "In1.Cu" signal "GND")
		(6 "In2.Cu" signal "IN1")
		(8 "In3.Cu" signal "GND1")
		(10 "In4.Cu" signal "IN2")
		(12 "In5.Cu" signal "GND2")
		(14 "In6.Cu" signal "IN3")
		(16 "In7.Cu" signal "GND3")
		(18 "In8.Cu" signal "VCC")
		(20 "In9.Cu" signal "VCC1")
		(22 "In10.Cu" signal "GND4")
		(24 "In11.Cu" signal "IN4")
		(26 "In12.Cu" signal "GND5")
		(28 "In13.Cu" signal "IN5")
		(30 "In14.Cu" signal "GND6")
		(32 "In15.Cu" signal "IN6")
		(34 "In16.Cu" signal "GND7")
		(2 "B.Cu" signal "BOTTOM")
		(9 "F.Adhes" user "F.Adhesive")
		(11 "B.Adhes" user "B.Adhesive")
		(13 "F.Paste" user "Package Geometry/Pastemask Top")
		(15 "B.Paste" user "Package Geometry/Pastemask Bottom")
		(5 "F.SilkS" user "Ref Des/Silkscreen Top")
		(7 "B.SilkS" user "Ref Des/Silkscreen Bottom")
		(1 "F.Mask" user "Board Geometry/Soldermask Top")
		(3 "B.Mask" user "Board Geometry/Soldermask Bottom")
		(17 "Dwgs.User" user "User.Drawings")
		(19 "Cmts.User" user "User.Comments")
		(21 "Eco1.User" user "User.Eco1")
		(23 "Eco2.User" user "User.Eco2")
		(25 "Edge.Cuts" user "Board Geometry/Outline")
		(27 "Margin" user)
		(31 "F.CrtYd" user "Package Geometry/Place Bound Top")
		(29 "B.CrtYd" user "Package Geometry/Place Bound Bottom")
		(35 "F.Fab" user "Ref Des/Assembly Top")
		(33 "B.Fab" user "Ref Des/Assembly Bottom")
	)
	(footprint ""
		(layer "F.Cu")
		(at 12.741148 -385.91109 180)
		(property "Reference" "PC6622"
			(at 0 0 180)
			(layer "F.SilkS")
			(hide yes)
			(effects
				(font
					(size 1.27 1.27)
				)
			)
		)
		(property "Value" ""
			(at 0 0 180)
			(layer "F.Fab")
			(effects
				(font
					(size 1.27 1.27)
				)
			)
		)
		(duplicate_pad_numbers_are_jumpers no)
		(fp_line
			(start 0.7874 0.4064)
			(end -0.7874 0.4064)
			(stroke
				(width 0.1524)
				(type default)
			)
			(layer "F.SilkS")
		)
		(fp_line
			(start 0.7874 -0.4064)
			(end 0.7874 0.4064)
			(stroke
				(width 0.1524)
				(type default)
			)
			(layer "F.SilkS")
		)
		(fp_line
			(start -0.7874 0.4064)
			(end -0.7874 -0.4064)
			(stroke
				(width 0.1524)
				(type default)
			)
			(layer "F.SilkS")
		)
		(fp_line
			(start -0.7874 -0.4064)
			(end 0.7874 -0.4064)
			(stroke
				(width 0.1524)
				(type default)
			)
			(layer "F.SilkS")
		)
		(fp_line
			(start 0.67945 0.3048)
			(end 0.120396 0.3048)
			(stroke
				(width 0.1)
				(type default)
			)
			(layer "F.Fab")
		)
		(fp_line
			(start 0.67945 -0.3048)
			(end 0.67945 0.3048)
			(stroke
				(width 0.1)
				(type default)
			)
			(layer "F.Fab")
		)
		(fp_line
			(start 0.12065 -0.2794)
			(end 0.12065 -0.3048)
			(stroke
				(width 0.1)
				(type default)
			)
			(layer "F.Fab")
		)
		(fp_line
			(start 0.12065 -0.3048)
			(end 0.67945 -0.3048)
			(stroke
				(width 0.1)
				(type default)
			)
			(layer "F.Fab")
		)
		(fp_line
			(start 0.120396 0.3048)
			(end 0.120396 0.2794)
			(stroke
				(width 0.1)
				(type default)
			)
			(layer "F.Fab")
		)
		(fp_line
			(start 0.120396 0.2794)
			(end -0.12065 0.2794)
			(stroke
				(width 0.1)
				(type default)
			)
			(layer "F.Fab")
		)
		(fp_line
			(start -0.12065 0.3048)
			(end -0.67945 0.3048)
			(stroke
				(width 0.1)
				(type default)
			)
			(layer "F.Fab")
		)
		(fp_line
			(start -0.12065 0.2794)
			(end -0.12065 0.3048)
			(stroke
				(width 0.1)
				(type default)
			)
			(layer "F.Fab")
		)
		(fp_line
			(start -0.12065 -0.2794)
			(end 0.12065 -0.2794)
			(stroke
				(width 0.1)
				(type default)
			)
			(layer "F.Fab")
		)
		(fp_line
			(start -0.12065 -0.305054)
			(end -0.12065 -0.2794)
			(stroke
				(width 0.1)
				(type default)
			)
			(layer "F.Fab")
		)
		(fp_line
			(start -0.67945 0.3048)
			(end -0.67945 -0.305054)
			(stroke
				(width 0.1)
				(type default)
			)
			(layer "F.Fab")
		)
		(fp_line
			(start -0.67945 -0.305054)
			(end -0.12065 -0.305054)
			(stroke
				(width 0.1)
				(type default)
			)
			(layer "F.Fab")
		)
		(pad "1" smd circle
			(at -0.40005 0 180)
			(size 0 0)
			(layers "F.Cu" "F.Mask" "F.Paste")
			(net "SW_P0V9_RETIMER_CPU1_SW1")
		)
		(pad "2" smd circle
			(at 0.40005 0 180)
			(size 0 0)
			(layers "F.Cu" "F.Mask" "F.Paste")
			(net "SW_P0V9_RETIMER_CPU1_SW1_RC")
		)
	)
	(footprint ""
		(layer "F.Cu")
		(at 17.32915 -68.128642 180)
		(property "Reference" "R1192"
			(at 0 0 180)
			(layer "F.SilkS")
			(hide yes)
			(effects
				(font
					(size 1.27 1.27)
				)
			)
		)
		(property "Value" ""
			(at 0 0 180)
			(layer "F.Fab")
			(effects
				(font
					(size 1.27 1.27)
				)
			)
		)
		(duplicate_pad_numbers_are_jumpers no)
		(fp_line
			(start 0.7874 0.4064)
			(end -0.7874 0.4064)
			(stroke
				(width 0.1524)
				(type default)
			)
			(layer "F.SilkS")
		)
		(fp_line
			(start 0.7874 -0.4064)
			(end 0.7874 0.4064)
			(stroke
				(width 0.1524)
				(type default)
			)
			(layer "F.SilkS")
		)
		(fp_line
			(start -0.7874 0.4064)
			(end -0.7874 -0.4064)
			(stroke
				(width 0.1524)
				(type default)
			)
			(layer "F.SilkS")
		)
		(fp_line
			(start -0.7874 -0.4064)
			(end 0.7874 -0.4064)
			(stroke
				(width 0.1524)
				(type default)
			)
			(layer "F.SilkS")
		)
		(fp_line
			(start 0.67945 0.3048)
			(end 0.120396 0.3048)
			(stroke
				(width 0.1)
				(type default)
			)
			(layer "F.Fab")
		)
		(fp_line
			(start 0.67945 -0.3048)
			(end 0.67945 0.3048)
			(stroke
				(width 0.1)
				(type default)
			)
			(layer "F.Fab")
		)
		(fp_line
			(start 0.12065 -0.2794)
			(end 0.12065 -0.3048)
			(stroke
				(width 0.1)
				(type default)
			)
			(layer "F.Fab")
		)
		(fp_line
			(start 0.12065 -0.3048)
			(end 0.67945 -0.3048)
			(stroke
				(width 0.1)
				(type default)
			)
			(layer "F.Fab")
		)
		(fp_line
			(start 0.120396 0.3048)
			(end 0.120396 0.2794)
			(stroke
				(width 0.1)
				(type default)
			)
			(layer "F.Fab")
		)
		(fp_line
			(start 0.120396 0.2794)
			(end -0.12065 0.2794)
			(stroke
				(width 0.1)
				(type default)
			)
			(layer "F.Fab")
		)
		(fp_line
			(start -0.12065 0.3048)
			(end -0.67945 0.3048)
			(stroke
				(width 0.1)
				(type default)
			)
			(layer "F.Fab")
		)
		(fp_line
			(start -0.12065 0.2794)
			(end -0.12065 0.3048)
			(stroke
				(width 0.1)
				(type default)
			)
			(layer "F.Fab")
		)
		(fp_line
			(start -0.12065 -0.2794)
			(end 0.12065 -0.2794)
			(stroke
				(width 0.1)
				(type default)
			)
			(layer "F.Fab")
		)
		(fp_line
			(start -0.12065 -0.305054)
			(end -0.12065 -0.2794)
			(stroke
				(width 0.1)
				(type default)
			)
			(layer "F.Fab")
		)
		(fp_line
			(start -0.67945 0.3048)
			(end -0.67945 -0.305054)
			(stroke
				(width 0.1)
				(type default)
			)
			(layer "F.Fab")
		)
		(fp_line
			(start -0.67945 -0.305054)
			(end -0.12065 -0.305054)
			(stroke
				(width 0.1)
				(type default)
			)
			(layer "F.Fab")
		)
		(pad "1" smd circle
			(at -0.40005 0 180)
			(size 0 0)
			(layers "F.Cu" "F.Mask" "F.Paste")
			(net "P3V3_AUX")
		)
		(pad "2" smd circle
			(at 0.40005 0 180)
			(size 0 0)
			(layers "F.Cu" "F.Mask" "F.Paste")
			(net "HP_LVC3_OCP_V3_2_PRSNT2_N")
		)
	)
	(footprint ""
		(layer "F.Cu")
		(at 333.215488 -402.548852 -90)
		(property "Reference" "R1020"
			(at 0 0 270)
			(layer "F.SilkS")
			(hide yes)
			(effects
				(font
					(size 1.27 1.27)
				)
			)
		)
		(property "Value" ""
			(at 0 0 270)
			(layer "F.Fab")
			(effects
				(font
					(size 1.27 1.27)
				)
			)
		)
		(duplicate_pad_numbers_are_jumpers no)
		(fp_line
			(start -0.32512 0.175006)
			(end -0.32512 -0.175006)
			(stroke
				(width 0.1)
				(type default)
			)
			(layer "F.Fab")
		)
		(fp_line
			(start 0.32512 0.175006)
			(end -0.32512 0.175006)
			(stroke
				(width 0.1)
				(type default)
			)
			(layer "F.Fab")
		)
		(fp_line
			(start -0.32512 -0.175006)
			(end 0.32512 -0.175006)
			(stroke
				(width 0.1)
				(type default)
			)
			(layer "F.Fab")
		)
		(fp_line
			(start 0.32512 -0.175006)
			(end 0.32512 0.175006)
			(stroke
				(width 0.1)
				(type default)
			)
			(layer "F.Fab")
		)
		(pad "1" smd rect
			(at -0.2667 0 270)
			(size 0.3048 0.381)
			(layers "F.Cu" "F.Mask" "F.Paste")
			(net "RST_RT_CPU0_P1_RESET_R_N")
		)
		(pad "2" smd rect
			(at 0.2667 0 90)
			(size 0.3048 0.381)
			(layers "F.Cu" "F.Mask" "F.Paste")
			(net "GND")
		)
	)
)
